(kicad_pcb
	(version 20260206)
	(generator "pcbnew")
	(generator_version "10.0")
	(general
		(thickness 1.6)
		(legacy_teardrops no)
	)
	(paper "A4")
	(title_block
		(title "Bryce Canyon_R.DPB_16317-1_OCP.brd")
		(comment 1 "Bryce Canyon / footprints 1497-1504 of 2099")
	)
	(layers
		(0 "F.Cu" signal "TOP")
		(4 "In1.Cu" signal "L2GND")
		(6 "In2.Cu" signal "L3")
		(8 "In3.Cu" signal "L4VCC")
		(10 "In4.Cu" signal "L5VCC")
		(12 "In5.Cu" signal "L6")
		(14 "In6.Cu" signal "L7GND")
		(2 "B.Cu" signal "BOTTOM")
		(9 "F.Adhes" user "F.Adhesive")
		(11 "B.Adhes" user "B.Adhesive")
		(13 "F.Paste" user "Package Geometry/Pastemask Top")
		(15 "B.Paste" user "Package Geometry/Pastemask Bottom")
		(5 "F.SilkS" user "Ref Des/Silkscreen Top")
		(7 "B.SilkS" user "Ref Des/Silkscreen Bottom")
		(1 "F.Mask" user "Board Geometry/Soldermask Top")
		(3 "B.Mask" user "Board Geometry/Soldermask Bottom")
		(17 "Dwgs.User" user "User.Drawings")
		(19 "Cmts.User" user "User.Comments")
		(21 "Eco1.User" user "User.Eco1")
		(23 "Eco2.User" user "User.Eco2")
		(25 "Edge.Cuts" user "Board Geometry/Outline")
		(27 "Margin" user)
		(31 "F.CrtYd" user "Package Geometry/Place Bound Top")
		(29 "B.CrtYd" user "Package Geometry/Place Bound Bottom")
		(35 "F.Fab" user "Ref Des/Assembly Top")
		(33 "B.Fab" user "Ref Des/Assembly Bottom")
	)
	(footprint ""
		(layer "F.Cu")
		(at 144.526 -214.249)
		(property "Reference" "R269"
			(at 0 0 0)
			(layer "F.SilkS")
			(hide yes)
			(effects
				(font
					(size 1.27 1.27)
				)
			)
		)
		(property "Value" "91R3F-1-GP"
			(at -0.0254 -2.5146 0)
			(unlocked yes)
			(layer "F.Fab")
			(hide yes)
			(effects
				(font
					(size 1.016 1.016)
					(thickness 0.1524)
				)
			)
		)
		(property "Device Type" "R603H22"
			(at -0.0254 -4.0386 0)
			(unlocked yes)
			(layer "F.Fab")
			(hide yes)
			(effects
				(font
					(size 1.016 1.016)
					(thickness 0.1524)
				)
			)
		)
		(duplicate_pad_numbers_are_jumpers no)
		(fp_line
			(start -0.4826 0)
			(end -0.2032 0)
			(stroke
				(width 0.2032)
				(type default)
			)
			(layer "F.SilkS")
		)
		(fp_line
			(start 0.2032 0)
			(end 0.4826 0)
			(stroke
				(width 0.2032)
				(type default)
			)
			(layer "F.SilkS")
		)
		(fp_rect
			(start -0.5842 1.3335)
			(end 0.5842 -1.3335)
			(stroke
				(width 0)
				(type default)
			)
			(fill no)
			(layer "F.CrtYd")
		)
		(fp_rect
			(start -0.5842 1.3335)
			(end 0.5842 -1.3335)
			(stroke
				(width 0)
				(type default)
			)
			(fill no)
			(layer "F.Fab")
		)
		(pad "1" smd custom
			(at 0 -0.762)
			(size 0.2159 0.2159)
			(layers "F.Cu" "F.Mask" "F.Paste")
			(net "P5V_B_1")
			(options
				(clearance outline)
				(anchor circle)
			)
			(primitives
				(gr_poly
					(pts
						(arc
							(start -0.3302 -0.4318)
							(mid -0.402042 -0.402042)
							(end -0.4318 -0.3302)
						)
						(arc
							(start -0.4318 0.3302)
							(mid -0.402042 0.402042)
							(end -0.3302 0.4318)
						)
						(arc
							(start 0.3302 0.4318)
							(mid 0.402042 0.402042)
							(end 0.4318 0.3302)
						)
						(arc
							(start 0.4318 -0.3302)
							(mid 0.402042 -0.402042)
							(end 0.3302 -0.4318)
						)
					)
					(width 0)
					(fill yes)
				)
			)
		)
		(pad "2" smd custom
			(at 0 0.762)
			(size 0.2159 0.2159)
			(layers "F.Cu" "F.Mask" "F.Paste")
			(net "DRV_ACT_4")
			(options
				(clearance outline)
				(anchor circle)
			)
			(primitives
				(gr_poly
					(pts
						(arc
							(start -0.3302 -0.4318)
							(mid -0.402042 -0.402042)
							(end -0.4318 -0.3302)
						)
						(arc
							(start -0.4318 0.3302)
							(mid -0.402042 0.402042)
							(end -0.3302 0.4318)
						)
						(arc
							(start 0.3302 0.4318)
							(mid 0.402042 0.402042)
							(end 0.4318 0.3302)
						)
						(arc
							(start 0.4318 -0.3302)
							(mid 0.402042 -0.402042)
							(end 0.3302 -0.4318)
						)
					)
					(width 0)
					(fill yes)
				)
			)
		)
	)
	(footprint ""
		(layer "F.Cu")
		(at 57.18937 -364.243366 90)
		(property "Reference" "C521"
			(at 0 0 90)
			(layer "F.SilkS")
			(hide yes)
			(effects
				(font
					(size 1.27 1.27)
				)
			)
		)
		(property "Value" "SCD1U25V2KX-2-GP"
			(at 1.1811 -2.7051 90)
			(unlocked yes)
			(layer "F.Fab")
			(hide yes)
			(effects
				(font
					(size 1.016 1.016)
					(thickness 0.1524)
				)
			)
		)
		(property "Device Type" "C402H22"
			(at 1.1811 -4.2291 90)
			(unlocked yes)
			(layer "F.Fab")
			(hide yes)
			(effects
				(font
					(size 1.016 1.016)
					(thickness 0.1524)
				)
			)
		)
		(duplicate_pad_numbers_are_jumpers no)
		(fp_rect
			(start -0.4318 0.9525)
			(end 0.4318 -0.9525)
			(stroke
				(width 0)
				(type default)
			)
			(fill no)
			(layer "F.CrtYd")
		)
		(fp_rect
			(start -0.4318 0.9525)
			(end 0.4318 -0.9525)
			(stroke
				(width 0)
				(type default)
			)
			(fill no)
			(layer "F.Fab")
		)
		(pad "1" smd custom
			(at 0 -0.4445 90)
			(size 0.1524 0.1524)
			(layers "F.Cu" "F.Mask" "F.Paste")
			(net "P12V_FAN0")
			(options
				(clearance outline)
				(anchor circle)
			)
			(primitives
				(gr_poly
					(pts
						(arc
							(start 0.3048 -0.2032)
							(mid 0.275042 -0.275042)
							(end 0.2032 -0.3048)
						)
						(arc
							(start -0.2032 -0.3048)
							(mid -0.275042 -0.275042)
							(end -0.3048 -0.2032)
						)
						(arc
							(start -0.3048 0.2032)
							(mid -0.275042 0.275042)
							(end -0.2032 0.3048)
						)
						(arc
							(start 0.2032 0.3048)
							(mid 0.275042 0.275042)
							(end 0.3048 0.2032)
						)
					)
					(width 0)
					(fill yes)
				)
			)
		)
		(pad "2" smd custom
			(at 0 0.4445 90)
			(size 0.1524 0.1524)
			(layers "F.Cu" "F.Mask" "F.Paste")
			(net "GND")
			(options
				(clearance outline)
				(anchor circle)
			)
			(primitives
				(gr_poly
					(pts
						(arc
							(start 0.3048 -0.2032)
							(mid 0.275042 -0.275042)
							(end 0.2032 -0.3048)
						)
						(arc
							(start -0.2032 -0.3048)
							(mid -0.275042 -0.275042)
							(end -0.3048 -0.2032)
						)
						(arc
							(start -0.3048 0.2032)
							(mid -0.275042 0.275042)
							(end -0.2032 0.3048)
						)
						(arc
							(start 0.2032 0.3048)
							(mid 0.275042 0.275042)
							(end 0.3048 0.2032)
						)
					)
					(width 0)
					(fill yes)
				)
			)
		)
	)
	(footprint ""
		(layer "F.Cu")
		(at 128.93548 -14.990826 90)
		(property "Reference" "VIA55"
			(at 0 0 90)
			(layer "F.SilkS")
			(hide yes)
			(effects
				(font
					(size 1.27 1.27)
				)
			)
		)
		(property "Value" "100OHM-8L-2D36MM-L18-GP"
			(at 3.8989 0.5715 90)
			(unlocked yes)
			(layer "F.Fab")
			(hide yes)
			(effects
				(font
					(size 1.016 1.016)
					(thickness 0.1524)
				)
			)
		)
		(property "Device Type" "VIA-PCIE-4P-414097"
			(at 3.8989 -0.9525 90)
			(unlocked yes)
			(layer "F.Fab")
			(hide yes)
			(effects
				(font
					(size 1.016 1.016)
					(thickness 0.1524)
				)
			)
		)
		(duplicate_pad_numbers_are_jumpers no)
		(fp_rect
			(start -2.0701 0.4826)
			(end 2.0701 -0.4826)
			(stroke
				(width 0)
				(type default)
			)
			(fill no)
			(layer "F.CrtYd")
		)
		(fp_rect
			(start -2.0701 0.4826)
			(end 2.0701 -0.4826)
			(stroke
				(width 0)
				(type default)
			)
			(fill no)
			(layer "F.Fab")
		)
		(pad "1" thru_hole circle
			(at -1.5875 0 90)
			(size 0.508 0.508)
			(drill 0.254)
			(layers "*.Cu" "*.Mask")
			(remove_unused_layers no)
			(net "GND")
			(clearance 0.2286)
			(thermal_gap 0.2286)
		)
		(pad "2" thru_hole circle
			(at -0.5715 0 90)
			(size 0.508 0.508)
			(drill 0.254)
			(layers "*.Cu" "*.Mask")
			(remove_unused_layers no)
			(net "PHY_SCC_B_TO_DRV_B_27_DP")
			(clearance 0.2286)
			(thermal_gap 0.2286)
		)
		(pad "3" thru_hole circle
			(at 0.5715 0 90)
			(size 0.508 0.508)
			(drill 0.254)
			(layers "*.Cu" "*.Mask")
			(remove_unused_layers no)
			(net "PHY_SCC_B_TO_DRV_B_27_DN")
			(clearance 0.2286)
			(thermal_gap 0.2286)
		)
		(pad "4" thru_hole circle
			(at 1.5875 0 90)
			(size 0.508 0.508)
			(drill 0.254)
			(layers "*.Cu" "*.Mask")
			(remove_unused_layers no)
			(net "GND")
			(clearance 0.2286)
			(thermal_gap 0.2286)
		)
	)
	(footprint ""
		(layer "F.Cu")
		(at 363.601 -16.256 -90)
		(property "Reference" "Q161"
			(at 0 0 270)
			(layer "F.SilkS")
			(hide yes)
			(effects
				(font
					(size 1.27 1.27)
				)
			)
		)
		(property "Value" "2N7002KDW-GP"
			(at -2.3622 -8.2042 270)
			(unlocked yes)
			(layer "F.Fab")
			(hide yes)
			(effects
				(font
					(size 1.016 1.016)
					(thickness 0.1524)
				)
			)
		)
		(property "Device Type" "SOT-363H44"
			(at -2.3622 -10.1092 270)
			(unlocked yes)
			(layer "F.Fab")
			(hide yes)
			(effects
				(font
					(size 1.016 1.016)
					(thickness 0.1524)
				)
			)
		)
		(duplicate_pad_numbers_are_jumpers no)
		(fp_line
			(start -1.4478 1.7018)
			(end 1.4478 1.7018)
			(stroke
				(width 0.1524)
				(type default)
			)
			(layer "F.SilkS")
		)
		(fp_line
			(start 1.4478 1.7018)
			(end 1.4478 -1.7018)
			(stroke
				(width 0.1524)
				(type default)
			)
			(layer "F.SilkS")
		)
		(fp_line
			(start -1.27 1.524)
			(end -1.27 0.6604)
			(stroke
				(width 0.4826)
				(type default)
			)
			(layer "F.SilkS")
		)
		(fp_line
			(start -1.4478 -1.7018)
			(end -1.4478 1.7018)
			(stroke
				(width 0.1524)
				(type default)
			)
			(layer "F.SilkS")
		)
		(fp_line
			(start 1.4478 -1.7018)
			(end -1.4478 -1.7018)
			(stroke
				(width 0.1524)
				(type default)
			)
			(layer "F.SilkS")
		)
		(fp_poly
			(pts
				(xy -1.524 -1.778) (xy 1.524 -1.778) (xy 1.524 1.778) (xy -1.524 1.778)
			)
			(stroke
				(width 0)
				(type default)
			)
			(fill no)
			(layer "F.CrtYd")
		)
		(fp_poly
			(pts
				(xy -1.524 -1.778) (xy 1.524 -1.778) (xy 1.524 1.778) (xy -1.524 1.778)
			)
			(stroke
				(width 0)
				(type default)
			)
			(fill no)
			(layer "F.Fab")
		)
		(pad "1" smd rect
			(at -0.65024 0.9398 270)
			(size 0.4064 1.016)
			(layers "F.Cu" "F.Mask" "F.Paste")
			(net "GND")
		)
		(pad "2" smd rect
			(at 0 0.9398 270)
			(size 0.4064 1.016)
			(layers "F.Cu" "F.Mask" "F.Paste")
			(net "SW_PWR_R_HDD31")
		)
		(pad "3" smd rect
			(at 0.65024 0.9398 270)
			(size 0.4064 1.016)
			(layers "F.Cu" "F.Mask" "F.Paste")
			(net "SW_HDD_P31")
		)
		(pad "4" smd rect
			(at 0.65024 -0.9398 270)
			(size 0.4064 1.016)
			(layers "F.Cu" "F.Mask" "F.Paste")
			(net "GND")
		)
		(pad "5" smd rect
			(at 0 -0.9398 270)
			(size 0.4064 1.016)
			(layers "F.Cu" "F.Mask" "F.Paste")
			(net "SW_HDD_G31")
		)
		(pad "6" smd rect
			(at -0.65024 -0.9398 270)
			(size 0.4064 1.016)
			(layers "F.Cu" "F.Mask" "F.Paste")
			(net "SW_HDD_R31")
		)
	)
	(footprint ""
		(layer "F.Cu")
		(at 457.7842 -134.6454 90)
		(property "Reference" "R583"
			(at 0 0 90)
			(layer "F.SilkS")
			(hide yes)
			(effects
				(font
					(size 1.27 1.27)
				)
			)
		)
		(property "Value" "4K7R2J-2-GP"
			(at 0.064008 -3.993896 90)
			(unlocked yes)
			(layer "F.Fab")
			(hide yes)
			(effects
				(font
					(size 1.016 1.016)
					(thickness 0.1524)
				)
			)
		)
		(property "Device Type" "R402H16"
			(at 0.064008 -5.517896 90)
			(unlocked yes)
			(layer "F.Fab")
			(hide yes)
			(effects
				(font
					(size 1.016 1.016)
					(thickness 0.1524)
				)
			)
		)
		(duplicate_pad_numbers_are_jumpers no)
		(fp_line
			(start 0.508 -0.9398)
			(end -0.508 -0.9398)
			(stroke
				(width 0.1524)
				(type default)
			)
			(layer "F.SilkS")
		)
		(fp_line
			(start -0.508 -0.9398)
			(end -0.508 0.9398)
			(stroke
				(width 0.1524)
				(type default)
			)
			(layer "F.SilkS")
		)
		(fp_rect
			(start -0.508 0.9398)
			(end 0.508 -0.9398)
			(stroke
				(width 0)
				(type default)
			)
			(fill no)
			(layer "F.CrtYd")
		)
		(fp_rect
			(start -0.508 0.9398)
			(end 0.508 -0.9398)
			(stroke
				(width 0)
				(type default)
			)
			(fill no)
			(layer "F.Fab")
		)
		(pad "1" smd custom
			(at 0 -0.4445 90)
			(size 0.1397 0.1397)
			(layers "F.Cu" "F.Mask" "F.Paste")
			(net "P12V_B")
			(options
				(clearance outline)
				(anchor circle)
			)
			(primitives
				(gr_poly
					(pts
						(arc
							(start -0.1778 -0.2794)
							(mid -0.249642 -0.249642)
							(end -0.2794 -0.1778)
						)
						(arc
							(start -0.2794 0.1778)
							(mid -0.249642 0.249642)
							(end -0.1778 0.2794)
						)
						(arc
							(start 0.1778 0.2794)
							(mid 0.249642 0.249642)
							(end 0.2794 0.1778)
						)
						(arc
							(start 0.2794 -0.1778)
							(mid 0.249642 -0.249642)
							(end 0.1778 -0.2794)
						)
					)
					(width 0)
					(fill yes)
				)
			)
		)
		(pad "2" smd custom
			(at 0 0.4445 90)
			(size 0.1397 0.1397)
			(layers "F.Cu" "F.Mask" "F.Paste")
			(net "SW_HDD_P22")
			(options
				(clearance outline)
				(anchor circle)
			)
			(primitives
				(gr_poly
					(pts
						(arc
							(start -0.1778 -0.2794)
							(mid -0.249642 -0.249642)
							(end -0.2794 -0.1778)
						)
						(arc
							(start -0.2794 0.1778)
							(mid -0.249642 0.249642)
							(end -0.1778 0.2794)
						)
						(arc
							(start 0.1778 0.2794)
							(mid 0.249642 0.249642)
							(end 0.2794 0.1778)
						)
						(arc
							(start 0.2794 -0.1778)
							(mid 0.249642 -0.249642)
							(end 0.1778 -0.2794)
						)
					)
					(width 0)
					(fill yes)
				)
			)
		)
	)
	(footprint ""
		(layer "F.Cu")
		(at 44.225718 -110.86338 90)
		(property "Reference" "C640"
			(at 0 0 90)
			(layer "F.SilkS")
			(hide yes)
			(effects
				(font
					(size 1.27 1.27)
				)
			)
		)
		(property "Value" "SC10U16V5KX-7-GP-U"
			(at -0.0762 -6.1214 90)
			(unlocked yes)
			(layer "F.Fab")
			(hide yes)
			(effects
				(font
					(size 1.016 1.016)
					(thickness 0.1524)
				)
			)
		)
		(property "Device Type" "C805H58"
			(at -0.0762 -8.1534 90)
			(unlocked yes)
			(layer "F.Fab")
			(hide yes)
			(effects
				(font
					(size 1.016 1.016)
					(thickness 0.1524)
				)
			)
		)
		(duplicate_pad_numbers_are_jumpers no)
		(fp_line
			(start 0.635 0)
			(end -0.635 0)
			(stroke
				(width 0.508)
				(type default)
			)
			(layer "F.SilkS")
		)
		(fp_rect
			(start -0.9652 1.778)
			(end 0.9652 -1.778)
			(stroke
				(width 0)
				(type default)
			)
			(fill no)
			(layer "F.CrtYd")
		)
		(fp_poly
			(pts
				(xy -0.9652 -1.778) (xy 0.9652 -1.778) (xy 0.9652 1.778) (xy -0.9652 1.778)
			)
			(stroke
				(width 0)
				(type default)
			)
			(fill no)
			(layer "F.Fab")
		)
		(pad "1" smd rect
			(at 0 -0.9652 90)
			(size 1.397 1.143)
			(layers "F.Cu" "F.Mask" "F.Paste")
			(net "P12V_B_2_VIN_U32")
		)
		(pad "2" smd rect
			(at 0 0.9652 90)
			(size 1.397 1.143)
			(layers "F.Cu" "F.Mask" "F.Paste")
			(net "GND")
		)
	)
	(footprint ""
		(layer "F.Cu")
		(at 464.6168 -5.3086 -90)
		(property "Reference" "R139"
			(at 0 0 270)
			(layer "F.SilkS")
			(hide yes)
			(effects
				(font
					(size 1.27 1.27)
				)
			)
		)
		(property "Value" "4K7R2F-GP"
			(at 0.064008 -3.993896 270)
			(unlocked yes)
			(layer "F.Fab")
			(hide yes)
			(effects
				(font
					(size 1.016 1.016)
					(thickness 0.1524)
				)
			)
		)
		(property "Device Type" "R402H16"
			(at 0.064008 -5.517896 270)
			(unlocked yes)
			(layer "F.Fab")
			(hide yes)
			(effects
				(font
					(size 1.016 1.016)
					(thickness 0.1524)
				)
			)
		)
		(duplicate_pad_numbers_are_jumpers no)
		(fp_line
			(start -0.508 -0.9398)
			(end -0.508 0.9398)
			(stroke
				(width 0.1524)
				(type default)
			)
			(layer "F.SilkS")
		)
		(fp_line
			(start 0.508 -0.9398)
			(end -0.508 -0.9398)
			(stroke
				(width 0.1524)
				(type default)
			)
			(layer "F.SilkS")
		)
		(fp_rect
			(start -0.508 0.9398)
			(end 0.508 -0.9398)
			(stroke
				(width 0)
				(type default)
			)
			(fill no)
			(layer "F.CrtYd")
		)
		(fp_rect
			(start -0.508 0.9398)
			(end 0.508 -0.9398)
			(stroke
				(width 0)
				(type default)
			)
			(fill no)
			(layer "F.Fab")
		)
		(pad "1" smd custom
			(at 0 -0.4445 270)
			(size 0.1397 0.1397)
			(layers "F.Cu" "F.Mask" "F.Paste")
			(net "TEMP2_A2")
			(options
				(clearance outline)
				(anchor circle)
			)
			(primitives
				(gr_poly
					(pts
						(arc
							(start -0.1778 -0.2794)
							(mid -0.249642 -0.249642)
							(end -0.2794 -0.1778)
						)
						(arc
							(start -0.2794 0.1778)
							(mid -0.249642 0.249642)
							(end -0.1778 0.2794)
						)
						(arc
							(start 0.1778 0.2794)
							(mid 0.249642 0.249642)
							(end 0.2794 0.1778)
						)
						(arc
							(start 0.2794 -0.1778)
							(mid 0.249642 -0.249642)
							(end 0.1778 -0.2794)
						)
					)
					(width 0)
					(fill yes)
				)
			)
		)
		(pad "2" smd custom
			(at 0 0.4445 270)
			(size 0.1397 0.1397)
			(layers "F.Cu" "F.Mask" "F.Paste")
			(net "GND")
			(options
				(clearance outline)
				(anchor circle)
			)
			(primitives
				(gr_poly
					(pts
						(arc
							(start -0.1778 -0.2794)
							(mid -0.249642 -0.249642)
							(end -0.2794 -0.1778)
						)
						(arc
							(start -0.2794 0.1778)
							(mid -0.249642 0.249642)
							(end -0.1778 0.2794)
						)
						(arc
							(start 0.1778 0.2794)
							(mid 0.249642 0.249642)
							(end 0.2794 0.1778)
						)
						(arc
							(start 0.2794 -0.1778)
							(mid 0.249642 -0.249642)
							(end 0.1778 -0.2794)
						)
					)
					(width 0)
					(fill yes)
				)
			)
		)
	)
	(footprint ""
		(layer "F.Cu")
		(at 445.167004 -363.22 90)
		(property "Reference" "C537"
			(at 0 0 90)
			(layer "F.SilkS")
			(hide yes)
			(effects
				(font
					(size 1.27 1.27)
				)
			)
		)
		(property "Value" "SC1U25V3KX-GP"
			(at 0 -2.8194 90)
			(unlocked yes)
			(layer "F.Fab")
			(hide yes)
			(effects
				(font
					(size 1.016 1.016)
					(thickness 0.1524)
				)
			)
		)
		(property "Device Type" "C603H36"
			(at 0 -4.3434 90)
			(unlocked yes)
			(layer "F.Fab")
			(hide yes)
			(effects
				(font
					(size 1.016 1.016)
					(thickness 0.1524)
				)
			)
		)
		(duplicate_pad_numbers_are_jumpers no)
		(fp_line
			(start 0.508 0)
			(end -0.508 0)
			(stroke
				(width 0.2032)
				(type default)
			)
			(layer "F.SilkS")
		)
		(fp_rect
			(start -0.5842 1.3335)
			(end 0.5842 -1.3335)
			(stroke
				(width 0)
				(type default)
			)
			(fill no)
			(layer "F.CrtYd")
		)
		(fp_rect
			(start -0.5842 1.3335)
			(end 0.5842 -1.3335)
			(stroke
				(width 0)
				(type default)
			)
			(fill no)
			(layer "F.Fab")
		)
		(pad "1" smd custom
			(at 0 -0.762 90)
			(size 0.2159 0.2159)
			(layers "F.Cu" "F.Mask" "F.Paste")
			(net "P12V_FAN3")
			(options
				(clearance outline)
				(anchor circle)
			)
			(primitives
				(gr_poly
					(pts
						(arc
							(start -0.3302 -0.4318)
							(mid -0.402042 -0.402042)
							(end -0.4318 -0.3302)
						)
						(arc
							(start -0.4318 0.3302)
							(mid -0.402042 0.402042)
							(end -0.3302 0.4318)
						)
						(arc
							(start 0.3302 0.4318)
							(mid 0.402042 0.402042)
							(end 0.4318 0.3302)
						)
						(arc
							(start 0.4318 -0.3302)
							(mid 0.402042 -0.402042)
							(end 0.3302 -0.4318)
						)
					)
					(width 0)
					(fill yes)
				)
			)
		)
		(pad "2" smd custom
			(at 0 0.762 90)
			(size 0.2159 0.2159)
			(layers "F.Cu" "F.Mask" "F.Paste")
			(net "GND")
			(options
				(clearance outline)
				(anchor circle)
			)
			(primitives
				(gr_poly
					(pts
						(arc
							(start -0.3302 -0.4318)
							(mid -0.402042 -0.402042)
							(end -0.4318 -0.3302)
						)
						(arc
							(start -0.4318 0.3302)
							(mid -0.402042 0.402042)
							(end -0.3302 0.4318)
						)
						(arc
							(start 0.3302 0.4318)
							(mid 0.402042 0.402042)
							(end 0.4318 0.3302)
						)
						(arc
							(start 0.4318 -0.3302)
							(mid 0.402042 -0.402042)
							(end 0.3302 -0.4318)
						)
					)
					(width 0)
					(fill yes)
				)
			)
		)
	)
)
